(kicad_pcb
	(version 20260206)
	(generator "pcbnew")
	(generator_version "10.0")
	(general
		(thickness 1.6)
		(legacy_teardrops no)
	)
	(paper "A4")
	(title_block
		(title "12092022_DA0F0TFB6D0_F0T_FAN_BOARD_MP5048_D_brd_v02_OCP.brd")
		(comment 1 "Grand Teton / footprints 633-637 of 924")
	)
	(layers
		(0 "F.Cu" signal "TOP")
		(4 "In1.Cu" signal "GND")
		(6 "In2.Cu" signal "IN1")
		(8 "In3.Cu" signal "IN2")
		(10 "In4.Cu" signal "GND1")
		(2 "B.Cu" signal "BOTTOM")
		(9 "F.Adhes" user "F.Adhesive")
		(11 "B.Adhes" user "B.Adhesive")
		(13 "F.Paste" user "Package Geometry/Pastemask Top")
		(15 "B.Paste" user "Package Geometry/Pastemask Bottom")
		(5 "F.SilkS" user "Ref Des/Silkscreen Top")
		(7 "B.SilkS" user "Ref Des/Silkscreen Bottom")
		(1 "F.Mask" user "Board Geometry/Soldermask Top")
		(3 "B.Mask" user "Board Geometry/Soldermask Bottom")
		(17 "Dwgs.User" user "User.Drawings")
		(19 "Cmts.User" user "User.Comments")
		(21 "Eco1.User" user "User.Eco1")
		(23 "Eco2.User" user "User.Eco2")
		(25 "Edge.Cuts" user "Board Geometry/Outline")
		(27 "Margin" user)
		(31 "F.CrtYd" user "Package Geometry/Place Bound Top")
		(29 "B.CrtYd" user "Package Geometry/Place Bound Bottom")
		(35 "F.Fab" user "Ref Des/Assembly Top")
		(33 "B.Fab" user "Ref Des/Assembly Bottom")
	)
	(footprint ""
		(layer "F.Cu")
		(at 33.02 -209.451956 180)
		(property "Reference" "R5306"
			(at 0 0 180)
			(layer "F.SilkS")
			(hide yes)
			(effects
				(font
					(size 1.27 1.27)
				)
			)
		)
		(property "Value" ""
			(at 0 0 180)
			(layer "F.Fab")
			(effects
				(font
					(size 1.27 1.27)
				)
			)
		)
		(duplicate_pad_numbers_are_jumpers no)
		(fp_line
			(start 0.7874 0.4064)
			(end -0.7874 0.4064)
			(stroke
				(width 0.1524)
				(type default)
			)
			(layer "F.SilkS")
		)
		(fp_line
			(start 0.7874 -0.4064)
			(end 0.7874 0.4064)
			(stroke
				(width 0.1524)
				(type default)
			)
			(layer "F.SilkS")
		)
		(fp_line
			(start -0.7874 0.4064)
			(end -0.7874 -0.4064)
			(stroke
				(width 0.1524)
				(type default)
			)
			(layer "F.SilkS")
		)
		(fp_line
			(start -0.7874 -0.4064)
			(end 0.7874 -0.4064)
			(stroke
				(width 0.1524)
				(type default)
			)
			(layer "F.SilkS")
		)
		(fp_line
			(start 0.67945 0.3048)
			(end 0.120396 0.3048)
			(stroke
				(width 0.1)
				(type default)
			)
			(layer "F.Fab")
		)
		(fp_line
			(start 0.67945 -0.3048)
			(end 0.67945 0.3048)
			(stroke
				(width 0.1)
				(type default)
			)
			(layer "F.Fab")
		)
		(fp_line
			(start 0.12065 -0.2794)
			(end 0.12065 -0.3048)
			(stroke
				(width 0.1)
				(type default)
			)
			(layer "F.Fab")
		)
		(fp_line
			(start 0.12065 -0.3048)
			(end 0.67945 -0.3048)
			(stroke
				(width 0.1)
				(type default)
			)
			(layer "F.Fab")
		)
		(fp_line
			(start 0.120396 0.3048)
			(end 0.120396 0.2794)
			(stroke
				(width 0.1)
				(type default)
			)
			(layer "F.Fab")
		)
		(fp_line
			(start 0.120396 0.2794)
			(end -0.12065 0.2794)
			(stroke
				(width 0.1)
				(type default)
			)
			(layer "F.Fab")
		)
		(fp_line
			(start -0.12065 0.3048)
			(end -0.67945 0.3048)
			(stroke
				(width 0.1)
				(type default)
			)
			(layer "F.Fab")
		)
		(fp_line
			(start -0.12065 0.2794)
			(end -0.12065 0.3048)
			(stroke
				(width 0.1)
				(type default)
			)
			(layer "F.Fab")
		)
		(fp_line
			(start -0.12065 -0.2794)
			(end 0.12065 -0.2794)
			(stroke
				(width 0.1)
				(type default)
			)
			(layer "F.Fab")
		)
		(fp_line
			(start -0.12065 -0.305054)
			(end -0.12065 -0.2794)
			(stroke
				(width 0.1)
				(type default)
			)
			(layer "F.Fab")
		)
		(fp_line
			(start -0.67945 0.3048)
			(end -0.67945 -0.305054)
			(stroke
				(width 0.1)
				(type default)
			)
			(layer "F.Fab")
		)
		(fp_line
			(start -0.67945 -0.305054)
			(end -0.12065 -0.305054)
			(stroke
				(width 0.1)
				(type default)
			)
			(layer "F.Fab")
		)
		(pad "1" smd rect
			(at -0.40005 0)
			(size 0.4572 0.508)
			(layers "F.Cu" "F.Mask" "F.Paste")
			(net "FAN_1_TACH_IL_R")
		)
		(pad "2" smd rect
			(at 0.40005 0)
			(size 0.4572 0.508)
			(layers "F.Cu" "F.Mask" "F.Paste")
			(net "FAN_1_TACH_IL")
		)
	)
	(footprint ""
		(layer "F.Cu")
		(at 37.338 -112.452912 180)
		(property "Reference" "R5224"
			(at 0 0 180)
			(layer "F.SilkS")
			(hide yes)
			(effects
				(font
					(size 1.27 1.27)
				)
			)
		)
		(property "Value" ""
			(at 0 0 180)
			(layer "F.Fab")
			(effects
				(font
					(size 1.27 1.27)
				)
			)
		)
		(duplicate_pad_numbers_are_jumpers no)
		(fp_line
			(start 0.7874 0.4064)
			(end -0.7874 0.4064)
			(stroke
				(width 0.1524)
				(type default)
			)
			(layer "F.SilkS")
		)
		(fp_line
			(start 0.7874 -0.4064)
			(end 0.7874 0.4064)
			(stroke
				(width 0.1524)
				(type default)
			)
			(layer "F.SilkS")
		)
		(fp_line
			(start -0.7874 0.4064)
			(end -0.7874 -0.4064)
			(stroke
				(width 0.1524)
				(type default)
			)
			(layer "F.SilkS")
		)
		(fp_line
			(start -0.7874 -0.4064)
			(end 0.7874 -0.4064)
			(stroke
				(width 0.1524)
				(type default)
			)
			(layer "F.SilkS")
		)
		(fp_line
			(start 0.67945 0.3048)
			(end 0.120396 0.3048)
			(stroke
				(width 0.1)
				(type default)
			)
			(layer "F.Fab")
		)
		(fp_line
			(start 0.67945 -0.3048)
			(end 0.67945 0.3048)
			(stroke
				(width 0.1)
				(type default)
			)
			(layer "F.Fab")
		)
		(fp_line
			(start 0.12065 -0.2794)
			(end 0.12065 -0.3048)
			(stroke
				(width 0.1)
				(type default)
			)
			(layer "F.Fab")
		)
		(fp_line
			(start 0.12065 -0.3048)
			(end 0.67945 -0.3048)
			(stroke
				(width 0.1)
				(type default)
			)
			(layer "F.Fab")
		)
		(fp_line
			(start 0.120396 0.3048)
			(end 0.120396 0.2794)
			(stroke
				(width 0.1)
				(type default)
			)
			(layer "F.Fab")
		)
		(fp_line
			(start 0.120396 0.2794)
			(end -0.12065 0.2794)
			(stroke
				(width 0.1)
				(type default)
			)
			(layer "F.Fab")
		)
		(fp_line
			(start -0.12065 0.3048)
			(end -0.67945 0.3048)
			(stroke
				(width 0.1)
				(type default)
			)
			(layer "F.Fab")
		)
		(fp_line
			(start -0.12065 0.2794)
			(end -0.12065 0.3048)
			(stroke
				(width 0.1)
				(type default)
			)
			(layer "F.Fab")
		)
		(fp_line
			(start -0.12065 -0.2794)
			(end 0.12065 -0.2794)
			(stroke
				(width 0.1)
				(type default)
			)
			(layer "F.Fab")
		)
		(fp_line
			(start -0.12065 -0.305054)
			(end -0.12065 -0.2794)
			(stroke
				(width 0.1)
				(type default)
			)
			(layer "F.Fab")
		)
		(fp_line
			(start -0.67945 0.3048)
			(end -0.67945 -0.305054)
			(stroke
				(width 0.1)
				(type default)
			)
			(layer "F.Fab")
		)
		(fp_line
			(start -0.67945 -0.305054)
			(end -0.12065 -0.305054)
			(stroke
				(width 0.1)
				(type default)
			)
			(layer "F.Fab")
		)
		(pad "1" smd circle
			(at -0.40005 0 180)
			(size 0 0)
			(layers "F.Cu" "F.Mask" "F.Paste")
			(net "SMB_FAN2_SDA_R")
		)
		(pad "2" smd circle
			(at 0.40005 0 180)
			(size 0 0)
			(layers "F.Cu" "F.Mask" "F.Paste")
			(net "SMB_FAN2_SDA")
		)
	)
	(footprint ""
		(layer "F.Cu")
		(at 43.561 -135.509 -90)
		(property "Reference" "R5561"
			(at 0 0 270)
			(layer "F.SilkS")
			(hide yes)
			(effects
				(font
					(size 1.27 1.27)
				)
			)
		)
		(property "Value" ""
			(at 0 0 270)
			(layer "F.Fab")
			(effects
				(font
					(size 1.27 1.27)
				)
			)
		)
		(duplicate_pad_numbers_are_jumpers no)
		(fp_line
			(start -0.7874 0.4064)
			(end -0.7874 -0.4064)
			(stroke
				(width 0.1524)
				(type default)
			)
			(layer "F.SilkS")
		)
		(fp_line
			(start 0.7874 0.4064)
			(end -0.7874 0.4064)
			(stroke
				(width 0.1524)
				(type default)
			)
			(layer "F.SilkS")
		)
		(fp_line
			(start -0.7874 -0.4064)
			(end 0.7874 -0.4064)
			(stroke
				(width 0.1524)
				(type default)
			)
			(layer "F.SilkS")
		)
		(fp_line
			(start 0.7874 -0.4064)
			(end 0.7874 0.4064)
			(stroke
				(width 0.1524)
				(type default)
			)
			(layer "F.SilkS")
		)
		(fp_line
			(start -0.67945 0.3048)
			(end -0.67945 -0.305054)
			(stroke
				(width 0.1)
				(type default)
			)
			(layer "F.Fab")
		)
		(fp_line
			(start -0.12065 0.3048)
			(end -0.67945 0.3048)
			(stroke
				(width 0.1)
				(type default)
			)
			(layer "F.Fab")
		)
		(fp_line
			(start 0.120396 0.3048)
			(end 0.120396 0.2794)
			(stroke
				(width 0.1)
				(type default)
			)
			(layer "F.Fab")
		)
		(fp_line
			(start 0.67945 0.3048)
			(end 0.120396 0.3048)
			(stroke
				(width 0.1)
				(type default)
			)
			(layer "F.Fab")
		)
		(fp_line
			(start -0.12065 0.2794)
			(end -0.12065 0.3048)
			(stroke
				(width 0.1)
				(type default)
			)
			(layer "F.Fab")
		)
		(fp_line
			(start 0.120396 0.2794)
			(end -0.12065 0.2794)
			(stroke
				(width 0.1)
				(type default)
			)
			(layer "F.Fab")
		)
		(fp_line
			(start -0.12065 -0.2794)
			(end 0.12065 -0.2794)
			(stroke
				(width 0.1)
				(type default)
			)
			(layer "F.Fab")
		)
		(fp_line
			(start 0.12065 -0.2794)
			(end 0.12065 -0.3048)
			(stroke
				(width 0.1)
				(type default)
			)
			(layer "F.Fab")
		)
		(fp_line
			(start 0.12065 -0.3048)
			(end 0.67945 -0.3048)
			(stroke
				(width 0.1)
				(type default)
			)
			(layer "F.Fab")
		)
		(fp_line
			(start 0.67945 -0.3048)
			(end 0.67945 0.3048)
			(stroke
				(width 0.1)
				(type default)
			)
			(layer "F.Fab")
		)
		(fp_line
			(start -0.67945 -0.305054)
			(end -0.12065 -0.305054)
			(stroke
				(width 0.1)
				(type default)
			)
			(layer "F.Fab")
		)
		(fp_line
			(start -0.12065 -0.305054)
			(end -0.12065 -0.2794)
			(stroke
				(width 0.1)
				(type default)
			)
			(layer "F.Fab")
		)
		(pad "1" smd circle
			(at -0.40005 0 270)
			(size 0 0)
			(layers "F.Cu" "F.Mask" "F.Paste")
			(net "P3V3_AUX")
		)
		(pad "2" smd circle
			(at 0.40005 0 270)
			(size 0 0)
			(layers "F.Cu" "F.Mask" "F.Paste")
			(net "U403_ADD1")
		)
	)
	(footprint ""
		(layer "F.Cu")
		(at 18.415 -17.526 90)
		(property "Reference" "R5310"
			(at 0 0 90)
			(layer "F.SilkS")
			(hide yes)
			(effects
				(font
					(size 1.27 1.27)
				)
			)
		)
		(property "Value" ""
			(at 0 0 90)
			(layer "F.Fab")
			(effects
				(font
					(size 1.27 1.27)
				)
			)
		)
		(duplicate_pad_numbers_are_jumpers no)
		(fp_line
			(start 0.7874 -0.4064)
			(end 0.7874 0.4064)
			(stroke
				(width 0.1524)
				(type default)
			)
			(layer "F.SilkS")
		)
		(fp_line
			(start -0.7874 -0.4064)
			(end 0.7874 -0.4064)
			(stroke
				(width 0.1524)
				(type default)
			)
			(layer "F.SilkS")
		)
		(fp_line
			(start 0.7874 0.4064)
			(end -0.7874 0.4064)
			(stroke
				(width 0.1524)
				(type default)
			)
			(layer "F.SilkS")
		)
		(fp_line
			(start -0.7874 0.4064)
			(end -0.7874 -0.4064)
			(stroke
				(width 0.1524)
				(type default)
			)
			(layer "F.SilkS")
		)
		(fp_line
			(start -0.12065 -0.305054)
			(end -0.12065 -0.2794)
			(stroke
				(width 0.1)
				(type default)
			)
			(layer "F.Fab")
		)
		(fp_line
			(start -0.67945 -0.305054)
			(end -0.12065 -0.305054)
			(stroke
				(width 0.1)
				(type default)
			)
			(layer "F.Fab")
		)
		(fp_line
			(start 0.67945 -0.3048)
			(end 0.67945 0.3048)
			(stroke
				(width 0.1)
				(type default)
			)
			(layer "F.Fab")
		)
		(fp_line
			(start 0.12065 -0.3048)
			(end 0.67945 -0.3048)
			(stroke
				(width 0.1)
				(type default)
			)
			(layer "F.Fab")
		)
		(fp_line
			(start 0.12065 -0.2794)
			(end 0.12065 -0.3048)
			(stroke
				(width 0.1)
				(type default)
			)
			(layer "F.Fab")
		)
		(fp_line
			(start -0.12065 -0.2794)
			(end 0.12065 -0.2794)
			(stroke
				(width 0.1)
				(type default)
			)
			(layer "F.Fab")
		)
		(fp_line
			(start 0.120396 0.2794)
			(end -0.12065 0.2794)
			(stroke
				(width 0.1)
				(type default)
			)
			(layer "F.Fab")
		)
		(fp_line
			(start -0.12065 0.2794)
			(end -0.12065 0.3048)
			(stroke
				(width 0.1)
				(type default)
			)
			(layer "F.Fab")
		)
		(fp_line
			(start 0.67945 0.3048)
			(end 0.120396 0.3048)
			(stroke
				(width 0.1)
				(type default)
			)
			(layer "F.Fab")
		)
		(fp_line
			(start 0.120396 0.3048)
			(end 0.120396 0.2794)
			(stroke
				(width 0.1)
				(type default)
			)
			(layer "F.Fab")
		)
		(fp_line
			(start -0.12065 0.3048)
			(end -0.67945 0.3048)
			(stroke
				(width 0.1)
				(type default)
			)
			(layer "F.Fab")
		)
		(fp_line
			(start -0.67945 0.3048)
			(end -0.67945 -0.305054)
			(stroke
				(width 0.1)
				(type default)
			)
			(layer "F.Fab")
		)
		(pad "1" smd rect
			(at -0.40005 0 270)
			(size 0.4572 0.508)
			(layers "F.Cu" "F.Mask" "F.Paste")
			(net "FAN_4_TACH_IL_R")
		)
		(pad "2" smd rect
			(at 0.40005 0 270)
			(size 0.4572 0.508)
			(layers "F.Cu" "F.Mask" "F.Paste")
			(net "FAN_4_TACH_IL")
		)
	)
	(footprint ""
		(layer "F.Cu")
		(at 26.67 -160.02 90)
		(property "Reference" "R4880"
			(at 0 0 90)
			(layer "F.SilkS")
			(hide yes)
			(effects
				(font
					(size 1.27 1.27)
				)
			)
		)
		(property "Value" ""
			(at 0 0 90)
			(layer "F.Fab")
			(effects
				(font
					(size 1.27 1.27)
				)
			)
		)
		(duplicate_pad_numbers_are_jumpers no)
		(fp_line
			(start 0.7874 -0.4064)
			(end 0.7874 0.4064)
			(stroke
				(width 0.1524)
				(type default)
			)
			(layer "F.SilkS")
		)
		(fp_line
			(start -0.7874 -0.4064)
			(end 0.7874 -0.4064)
			(stroke
				(width 0.1524)
				(type default)
			)
			(layer "F.SilkS")
		)
		(fp_line
			(start 0.7874 0.4064)
			(end -0.7874 0.4064)
			(stroke
				(width 0.1524)
				(type default)
			)
			(layer "F.SilkS")
		)
		(fp_line
			(start -0.7874 0.4064)
			(end -0.7874 -0.4064)
			(stroke
				(width 0.1524)
				(type default)
			)
			(layer "F.SilkS")
		)
		(fp_line
			(start -0.12065 -0.305054)
			(end -0.12065 -0.2794)
			(stroke
				(width 0.1)
				(type default)
			)
			(layer "F.Fab")
		)
		(fp_line
			(start -0.67945 -0.305054)
			(end -0.12065 -0.305054)
			(stroke
				(width 0.1)
				(type default)
			)
			(layer "F.Fab")
		)
		(fp_line
			(start 0.67945 -0.3048)
			(end 0.67945 0.3048)
			(stroke
				(width 0.1)
				(type default)
			)
			(layer "F.Fab")
		)
		(fp_line
			(start 0.12065 -0.3048)
			(end 0.67945 -0.3048)
			(stroke
				(width 0.1)
				(type default)
			)
			(layer "F.Fab")
		)
		(fp_line
			(start 0.12065 -0.2794)
			(end 0.12065 -0.3048)
			(stroke
				(width 0.1)
				(type default)
			)
			(layer "F.Fab")
		)
		(fp_line
			(start -0.12065 -0.2794)
			(end 0.12065 -0.2794)
			(stroke
				(width 0.1)
				(type default)
			)
			(layer "F.Fab")
		)
		(fp_line
			(start 0.120396 0.2794)
			(end -0.12065 0.2794)
			(stroke
				(width 0.1)
				(type default)
			)
			(layer "F.Fab")
		)
		(fp_line
			(start -0.12065 0.2794)
			(end -0.12065 0.3048)
			(stroke
				(width 0.1)
				(type default)
			)
			(layer "F.Fab")
		)
		(fp_line
			(start 0.67945 0.3048)
			(end 0.120396 0.3048)
			(stroke
				(width 0.1)
				(type default)
			)
			(layer "F.Fab")
		)
		(fp_line
			(start 0.120396 0.3048)
			(end 0.120396 0.2794)
			(stroke
				(width 0.1)
				(type default)
			)
			(layer "F.Fab")
		)
		(fp_line
			(start -0.12065 0.3048)
			(end -0.67945 0.3048)
			(stroke
				(width 0.1)
				(type default)
			)
			(layer "F.Fab")
		)
		(fp_line
			(start -0.67945 0.3048)
			(end -0.67945 -0.305054)
			(stroke
				(width 0.1)
				(type default)
			)
			(layer "F.Fab")
		)
		(pad "1" smd circle
			(at -0.40005 0 90)
			(size 0 0)
			(layers "F.Cu" "F.Mask" "F.Paste")
			(net "SMB_FAN6_R_SDA")
		)
		(pad "2" smd circle
			(at 0.40005 0 90)
			(size 0 0)
			(layers "F.Cu" "F.Mask" "F.Paste")
			(net "SMB_FAN6_SDA")
		)
	)
)
